(kicad_pcb
	(version 20260206)
	(generator "pcbnew")
	(generator_version "10.0")
	(general
		(thickness 1.6)
		(legacy_teardrops no)
	)
	(paper "A4")
	(title_block
		(title "peb — Lightning_PEB_BRD.brd")
		(comment 1 "Lightning (Wiwynn / Facebook NVMe JBOF) / footprints 1604-1609 of 2563")
	)
	(layers
		(0 "F.Cu" signal "TOP")
		(4 "In1.Cu" signal "L2GND")
		(6 "In2.Cu" signal "L3")
		(8 "In3.Cu" signal "L4VCC")
		(10 "In4.Cu" signal "L5VCC")
		(12 "In5.Cu" signal "L6")
		(14 "In6.Cu" signal "L7GND")
		(2 "B.Cu" signal "BOTTOM")
		(9 "F.Adhes" user "F.Adhesive")
		(11 "B.Adhes" user "B.Adhesive")
		(13 "F.Paste" user "Package Geometry/Pastemask Top")
		(15 "B.Paste" user "Package Geometry/Pastemask Bottom")
		(5 "F.SilkS" user "Ref Des/Silkscreen Top")
		(7 "B.SilkS" user "Ref Des/Silkscreen Bottom")
		(1 "F.Mask" user "Board Geometry/Soldermask Top")
		(3 "B.Mask" user "Board Geometry/Soldermask Bottom")
		(17 "Dwgs.User" user "User.Drawings")
		(19 "Cmts.User" user "User.Comments")
		(21 "Eco1.User" user "User.Eco1")
		(23 "Eco2.User" user "User.Eco2")
		(25 "Edge.Cuts" user "Board Geometry/Outline")
		(27 "Margin" user)
		(31 "F.CrtYd" user "Package Geometry/Place Bound Top")
		(29 "B.CrtYd" user "Package Geometry/Place Bound Bottom")
		(35 "F.Fab" user "Ref Des/Assembly Top")
		(33 "B.Fab" user "Ref Des/Assembly Bottom")
	)
	(footprint ""
		(layer "F.Cu")
		(at 14.5288 -175.8442)
		(property "Reference" "PR39"
			(at 0 0 0)
			(layer "F.SilkS")
			(hide yes)
			(effects
				(font
					(size 1.27 1.27)
				)
			)
		)
		(property "Value" "10KR2F-2-GP"
			(at 0.064008 -3.993896 0)
			(unlocked yes)
			(layer "F.Fab")
			(hide yes)
			(effects
				(font
					(size 1.016 1.016)
					(thickness 0.1524)
				)
			)
		)
		(property "Device Type" "R402H16"
			(at 0.064008 -5.517896 0)
			(unlocked yes)
			(layer "F.Fab")
			(hide yes)
			(effects
				(font
					(size 1.016 1.016)
					(thickness 0.1524)
				)
			)
		)
		(duplicate_pad_numbers_are_jumpers no)
		(fp_line
			(start -0.508 -0.9398)
			(end -0.508 0.9398)
			(stroke
				(width 0.1524)
				(type default)
			)
			(layer "F.SilkS")
		)
		(fp_line
			(start 0.508 -0.9398)
			(end -0.508 -0.9398)
			(stroke
				(width 0.1524)
				(type default)
			)
			(layer "F.SilkS")
		)
		(fp_rect
			(start -0.508 0.9398)
			(end 0.508 -0.9398)
			(stroke
				(width 0)
				(type default)
			)
			(fill no)
			(layer "F.CrtYd")
		)
		(fp_rect
			(start -0.508 0.9398)
			(end 0.508 -0.9398)
			(stroke
				(width 0)
				(type default)
			)
			(fill no)
			(layer "F.Fab")
		)
		(pad "1" smd custom
			(at 0 -0.4445)
			(size 0.1397 0.1397)
			(layers "F.Cu" "F.Mask" "F.Paste")
			(net "GND")
			(options
				(clearance outline)
				(anchor circle)
			)
			(primitives
				(gr_poly
					(pts
						(arc
							(start -0.1778 -0.2794)
							(mid -0.249642 -0.249642)
							(end -0.2794 -0.1778)
						)
						(arc
							(start -0.2794 0.1778)
							(mid -0.249642 0.249642)
							(end -0.1778 0.2794)
						)
						(arc
							(start 0.1778 0.2794)
							(mid 0.249642 0.249642)
							(end 0.2794 0.1778)
						)
						(arc
							(start 0.2794 -0.1778)
							(mid 0.249642 -0.249642)
							(end 0.1778 -0.2794)
						)
					)
					(width 0)
					(fill yes)
				)
			)
		)
		(pad "2" smd custom
			(at 0 0.4445)
			(size 0.1397 0.1397)
			(layers "F.Cu" "F.Mask" "F.Paste")
			(net "TRAY_MBP_CTRL_EN_N")
			(options
				(clearance outline)
				(anchor circle)
			)
			(primitives
				(gr_poly
					(pts
						(arc
							(start -0.1778 -0.2794)
							(mid -0.249642 -0.249642)
							(end -0.2794 -0.1778)
						)
						(arc
							(start -0.2794 0.1778)
							(mid -0.249642 0.249642)
							(end -0.1778 0.2794)
						)
						(arc
							(start 0.1778 0.2794)
							(mid 0.249642 0.249642)
							(end 0.2794 0.1778)
						)
						(arc
							(start 0.2794 -0.1778)
							(mid 0.249642 -0.249642)
							(end 0.1778 -0.2794)
						)
					)
					(width 0)
					(fill yes)
				)
			)
		)
	)
	(footprint ""
		(layer "F.Cu")
		(at 320.675 -86.487 180)
		(property "Reference" "R568"
			(at 0 0 180)
			(layer "F.SilkS")
			(hide yes)
			(effects
				(font
					(size 1.27 1.27)
				)
			)
		)
		(property "Value" "10KR2F-2-GP"
			(at 0.064008 -3.993896 180)
			(unlocked yes)
			(layer "F.Fab")
			(hide yes)
			(effects
				(font
					(size 1.016 1.016)
					(thickness 0.1524)
				)
			)
		)
		(property "Device Type" "R402H16"
			(at 0.064008 -5.517896 180)
			(unlocked yes)
			(layer "F.Fab")
			(hide yes)
			(effects
				(font
					(size 1.016 1.016)
					(thickness 0.1524)
				)
			)
		)
		(duplicate_pad_numbers_are_jumpers no)
		(fp_line
			(start 0.508 -0.9398)
			(end -0.508 -0.9398)
			(stroke
				(width 0.1524)
				(type default)
			)
			(layer "F.SilkS")
		)
		(fp_line
			(start -0.508 -0.9398)
			(end -0.508 0.9398)
			(stroke
				(width 0.1524)
				(type default)
			)
			(layer "F.SilkS")
		)
		(fp_rect
			(start -0.508 0.9398)
			(end 0.508 -0.9398)
			(stroke
				(width 0)
				(type default)
			)
			(fill no)
			(layer "F.CrtYd")
		)
		(fp_rect
			(start -0.508 0.9398)
			(end 0.508 -0.9398)
			(stroke
				(width 0)
				(type default)
			)
			(fill no)
			(layer "F.Fab")
		)
		(pad "1" smd custom
			(at 0 -0.4445 180)
			(size 0.1397 0.1397)
			(layers "F.Cu" "F.Mask" "F.Paste")
			(net "P3V3_STBY")
			(options
				(clearance outline)
				(anchor circle)
			)
			(primitives
				(gr_poly
					(pts
						(arc
							(start -0.1778 -0.2794)
							(mid -0.249642 -0.249642)
							(end -0.2794 -0.1778)
						)
						(arc
							(start -0.2794 0.1778)
							(mid -0.249642 0.249642)
							(end -0.1778 0.2794)
						)
						(arc
							(start 0.1778 0.2794)
							(mid 0.249642 0.249642)
							(end 0.2794 0.1778)
						)
						(arc
							(start 0.2794 -0.1778)
							(mid 0.249642 -0.249642)
							(end 0.1778 -0.2794)
						)
					)
					(width 0)
					(fill yes)
				)
			)
		)
		(pad "2" smd custom
			(at 0 0.4445 180)
			(size 0.1397 0.1397)
			(layers "F.Cu" "F.Mask" "F.Paste")
			(net "IOEXP_PMC1_AD1")
			(options
				(clearance outline)
				(anchor circle)
			)
			(primitives
				(gr_poly
					(pts
						(arc
							(start -0.1778 -0.2794)
							(mid -0.249642 -0.249642)
							(end -0.2794 -0.1778)
						)
						(arc
							(start -0.2794 0.1778)
							(mid -0.249642 0.249642)
							(end -0.1778 0.2794)
						)
						(arc
							(start 0.1778 0.2794)
							(mid 0.249642 0.249642)
							(end 0.2794 0.1778)
						)
						(arc
							(start 0.2794 -0.1778)
							(mid 0.249642 -0.249642)
							(end 0.1778 -0.2794)
						)
					)
					(width 0)
					(fill yes)
				)
			)
		)
	)
	(footprint ""
		(layer "F.Cu")
		(at 41.783 -206.883)
		(property "Reference" "R883"
			(at 0 0 0)
			(layer "F.SilkS")
			(hide yes)
			(effects
				(font
					(size 1.27 1.27)
				)
			)
		)
		(property "Value" "0R2J-2-GP"
			(at 0.064008 -3.993896 0)
			(unlocked yes)
			(layer "F.Fab")
			(hide yes)
			(effects
				(font
					(size 1.016 1.016)
					(thickness 0.1524)
				)
			)
		)
		(property "Device Type" "R402H16"
			(at 0.064008 -5.517896 0)
			(unlocked yes)
			(layer "F.Fab")
			(hide yes)
			(effects
				(font
					(size 1.016 1.016)
					(thickness 0.1524)
				)
			)
		)
		(duplicate_pad_numbers_are_jumpers no)
		(fp_line
			(start -0.508 -0.9398)
			(end -0.508 0.9398)
			(stroke
				(width 0.1524)
				(type default)
			)
			(layer "F.SilkS")
		)
		(fp_line
			(start 0.508 -0.9398)
			(end -0.508 -0.9398)
			(stroke
				(width 0.1524)
				(type default)
			)
			(layer "F.SilkS")
		)
		(fp_rect
			(start -0.508 0.9398)
			(end 0.508 -0.9398)
			(stroke
				(width 0)
				(type default)
			)
			(fill no)
			(layer "F.CrtYd")
		)
		(fp_rect
			(start -0.508 0.9398)
			(end 0.508 -0.9398)
			(stroke
				(width 0)
				(type default)
			)
			(fill no)
			(layer "F.Fab")
		)
		(pad "1" smd custom
			(at 0 -0.4445)
			(size 0.1397 0.1397)
			(layers "F.Cu" "F.Mask" "F.Paste")
			(net "BUF_I2C6_C_FCB_SCL")
			(options
				(clearance outline)
				(anchor circle)
			)
			(primitives
				(gr_poly
					(pts
						(arc
							(start -0.1778 -0.2794)
							(mid -0.249642 -0.249642)
							(end -0.2794 -0.1778)
						)
						(arc
							(start -0.2794 0.1778)
							(mid -0.249642 0.249642)
							(end -0.1778 0.2794)
						)
						(arc
							(start 0.1778 0.2794)
							(mid 0.249642 0.249642)
							(end 0.2794 0.1778)
						)
						(arc
							(start 0.2794 -0.1778)
							(mid 0.249642 -0.249642)
							(end 0.1778 -0.2794)
						)
					)
					(width 0)
					(fill yes)
				)
			)
		)
		(pad "2" smd custom
			(at 0 0.4445)
			(size 0.1397 0.1397)
			(layers "F.Cu" "F.Mask" "F.Paste")
			(net "BUF_I2C6_C_FCB_SCL_R")
			(options
				(clearance outline)
				(anchor circle)
			)
			(primitives
				(gr_poly
					(pts
						(arc
							(start -0.1778 -0.2794)
							(mid -0.249642 -0.249642)
							(end -0.2794 -0.1778)
						)
						(arc
							(start -0.2794 0.1778)
							(mid -0.249642 0.249642)
							(end -0.1778 0.2794)
						)
						(arc
							(start 0.1778 0.2794)
							(mid 0.249642 0.249642)
							(end 0.2794 0.1778)
						)
						(arc
							(start 0.2794 -0.1778)
							(mid 0.249642 -0.249642)
							(end 0.1778 -0.2794)
						)
					)
					(width 0)
					(fill yes)
				)
			)
		)
	)
	(footprint ""
		(layer "F.Cu")
		(at 71.007986 -212.420454 180)
		(property "Reference" "C354"
			(at 0 0 180)
			(layer "F.SilkS")
			(hide yes)
			(effects
				(font
					(size 1.27 1.27)
				)
			)
		)
		(property "Value" "SCD22U10V2KX-1GP"
			(at 1.1811 -2.7051 180)
			(unlocked yes)
			(layer "F.Fab")
			(hide yes)
			(effects
				(font
					(size 1.016 1.016)
					(thickness 0.1524)
				)
			)
		)
		(property "Device Type" "C402H22"
			(at 1.1811 -4.2291 180)
			(unlocked yes)
			(layer "F.Fab")
			(hide yes)
			(effects
				(font
					(size 1.016 1.016)
					(thickness 0.1524)
				)
			)
		)
		(duplicate_pad_numbers_are_jumpers no)
		(fp_rect
			(start -0.4318 0.9525)
			(end 0.4318 -0.9525)
			(stroke
				(width 0)
				(type default)
			)
			(fill no)
			(layer "F.CrtYd")
		)
		(fp_rect
			(start -0.4318 0.9525)
			(end 0.4318 -0.9525)
			(stroke
				(width 0)
				(type default)
			)
			(fill no)
			(layer "F.Fab")
		)
		(pad "1" smd custom
			(at 0 -0.4445 180)
			(size 0.1524 0.1524)
			(layers "F.Cu" "F.Mask" "F.Paste")
			(net "PCIE_TX_CAP_N69")
			(options
				(clearance outline)
				(anchor circle)
			)
			(primitives
				(gr_poly
					(pts
						(arc
							(start 0.3048 -0.2032)
							(mid 0.275042 -0.275042)
							(end 0.2032 -0.3048)
						)
						(arc
							(start -0.2032 -0.3048)
							(mid -0.275042 -0.275042)
							(end -0.3048 -0.2032)
						)
						(arc
							(start -0.3048 0.2032)
							(mid -0.275042 0.275042)
							(end -0.2032 0.3048)
						)
						(arc
							(start 0.2032 0.3048)
							(mid 0.275042 0.275042)
							(end 0.3048 0.2032)
						)
					)
					(width 0)
					(fill yes)
				)
			)
		)
		(pad "2" smd custom
			(at 0 0.4445 180)
			(size 0.1524 0.1524)
			(layers "F.Cu" "F.Mask" "F.Paste")
			(net "PCIE_TX_N69")
			(options
				(clearance outline)
				(anchor circle)
			)
			(primitives
				(gr_poly
					(pts
						(arc
							(start 0.3048 -0.2032)
							(mid 0.275042 -0.275042)
							(end 0.2032 -0.3048)
						)
						(arc
							(start -0.2032 -0.3048)
							(mid -0.275042 -0.275042)
							(end -0.3048 -0.2032)
						)
						(arc
							(start -0.3048 0.2032)
							(mid -0.275042 0.275042)
							(end -0.2032 0.3048)
						)
						(arc
							(start 0.2032 0.3048)
							(mid 0.275042 0.275042)
							(end 0.3048 0.2032)
						)
					)
					(width 0)
					(fill yes)
				)
			)
		)
	)
	(footprint ""
		(layer "F.Cu")
		(at 213.932008 -4.064)
		(property "Reference" "R676"
			(at 0 0 0)
			(layer "F.SilkS")
			(hide yes)
			(effects
				(font
					(size 1.27 1.27)
				)
			)
		)
		(property "Value" "100KR2F-L1-GP"
			(at 0.064008 -3.993896 0)
			(unlocked yes)
			(layer "F.Fab")
			(hide yes)
			(effects
				(font
					(size 1.016 1.016)
					(thickness 0.1524)
				)
			)
		)
		(property "Device Type" "R402H16"
			(at 0.064008 -5.517896 0)
			(unlocked yes)
			(layer "F.Fab")
			(hide yes)
			(effects
				(font
					(size 1.016 1.016)
					(thickness 0.1524)
				)
			)
		)
		(duplicate_pad_numbers_are_jumpers no)
		(fp_line
			(start -0.508 -0.9398)
			(end -0.508 0.9398)
			(stroke
				(width 0.1524)
				(type default)
			)
			(layer "F.SilkS")
		)
		(fp_line
			(start 0.508 -0.9398)
			(end -0.508 -0.9398)
			(stroke
				(width 0.1524)
				(type default)
			)
			(layer "F.SilkS")
		)
		(fp_rect
			(start -0.508 0.9398)
			(end 0.508 -0.9398)
			(stroke
				(width 0)
				(type default)
			)
			(fill no)
			(layer "F.CrtYd")
		)
		(fp_rect
			(start -0.508 0.9398)
			(end 0.508 -0.9398)
			(stroke
				(width 0)
				(type default)
			)
			(fill no)
			(layer "F.Fab")
		)
		(pad "1" smd custom
			(at 0 -0.4445)
			(size 0.1397 0.1397)
			(layers "F.Cu" "F.Mask" "F.Paste")
			(net "HOST3_RST_N")
			(options
				(clearance outline)
				(anchor circle)
			)
			(primitives
				(gr_poly
					(pts
						(arc
							(start -0.1778 -0.2794)
							(mid -0.249642 -0.249642)
							(end -0.2794 -0.1778)
						)
						(arc
							(start -0.2794 0.1778)
							(mid -0.249642 0.249642)
							(end -0.1778 0.2794)
						)
						(arc
							(start 0.1778 0.2794)
							(mid 0.249642 0.249642)
							(end 0.2794 0.1778)
						)
						(arc
							(start 0.2794 -0.1778)
							(mid 0.249642 -0.249642)
							(end 0.1778 -0.2794)
						)
					)
					(width 0)
					(fill yes)
				)
			)
		)
		(pad "2" smd custom
			(at 0 0.4445)
			(size 0.1397 0.1397)
			(layers "F.Cu" "F.Mask" "F.Paste")
			(net "GND")
			(options
				(clearance outline)
				(anchor circle)
			)
			(primitives
				(gr_poly
					(pts
						(arc
							(start -0.1778 -0.2794)
							(mid -0.249642 -0.249642)
							(end -0.2794 -0.1778)
						)
						(arc
							(start -0.2794 0.1778)
							(mid -0.249642 0.249642)
							(end -0.1778 0.2794)
						)
						(arc
							(start 0.1778 0.2794)
							(mid 0.249642 0.249642)
							(end 0.2794 0.1778)
						)
						(arc
							(start 0.2794 -0.1778)
							(mid 0.249642 -0.249642)
							(end 0.1778 -0.2794)
						)
					)
					(width 0)
					(fill yes)
				)
			)
		)
	)
	(footprint ""
		(layer "F.Cu")
		(at 47.7901 -116.89207)
		(property "Reference" "R224"
			(at 0 0 0)
			(layer "F.SilkS")
			(hide yes)
			(effects
				(font
					(size 1.27 1.27)
				)
			)
		)
		(property "Value" "4K7R2F-GP"
			(at 0.064008 -3.993896 0)
			(unlocked yes)
			(layer "F.Fab")
			(hide yes)
			(effects
				(font
					(size 1.016 1.016)
					(thickness 0.1524)
				)
			)
		)
		(property "Device Type" "R402H16"
			(at 0.064008 -5.517896 0)
			(unlocked yes)
			(layer "F.Fab")
			(hide yes)
			(effects
				(font
					(size 1.016 1.016)
					(thickness 0.1524)
				)
			)
		)
		(duplicate_pad_numbers_are_jumpers no)
		(fp_line
			(start -0.508 -0.9398)
			(end -0.508 0.9398)
			(stroke
				(width 0.1524)
				(type default)
			)
			(layer "F.SilkS")
		)
		(fp_line
			(start 0.508 -0.9398)
			(end -0.508 -0.9398)
			(stroke
				(width 0.1524)
				(type default)
			)
			(layer "F.SilkS")
		)
		(fp_rect
			(start -0.508 0.9398)
			(end 0.508 -0.9398)
			(stroke
				(width 0)
				(type default)
			)
			(fill no)
			(layer "F.CrtYd")
		)
		(fp_rect
			(start -0.508 0.9398)
			(end 0.508 -0.9398)
			(stroke
				(width 0)
				(type default)
			)
			(fill no)
			(layer "F.Fab")
		)
		(pad "1" smd custom
			(at 0 -0.4445)
			(size 0.1397 0.1397)
			(layers "F.Cu" "F.Mask" "F.Paste")
			(net "BMC_USB_EN_1")
			(options
				(clearance outline)
				(anchor circle)
			)
			(primitives
				(gr_poly
					(pts
						(arc
							(start -0.1778 -0.2794)
							(mid -0.249642 -0.249642)
							(end -0.2794 -0.1778)
						)
						(arc
							(start -0.2794 0.1778)
							(mid -0.249642 0.249642)
							(end -0.1778 0.2794)
						)
						(arc
							(start 0.1778 0.2794)
							(mid 0.249642 0.249642)
							(end 0.2794 0.1778)
						)
						(arc
							(start 0.2794 -0.1778)
							(mid 0.249642 -0.249642)
							(end 0.1778 -0.2794)
						)
					)
					(width 0)
					(fill yes)
				)
			)
		)
		(pad "2" smd custom
			(at 0 0.4445)
			(size 0.1397 0.1397)
			(layers "F.Cu" "F.Mask" "F.Paste")
			(net "P3V3_STBY")
			(options
				(clearance outline)
				(anchor circle)
			)
			(primitives
				(gr_poly
					(pts
						(arc
							(start -0.1778 -0.2794)
							(mid -0.249642 -0.249642)
							(end -0.2794 -0.1778)
						)
						(arc
							(start -0.2794 0.1778)
							(mid -0.249642 0.249642)
							(end -0.1778 0.2794)
						)
						(arc
							(start 0.1778 0.2794)
							(mid 0.249642 0.249642)
							(end 0.2794 0.1778)
						)
						(arc
							(start 0.2794 -0.1778)
							(mid 0.249642 -0.249642)
							(end 0.1778 -0.2794)
						)
					)
					(width 0)
					(fill yes)
				)
			)
		)
	)
)
